# S9S_MB_2U (Grand Teton) — schematic netlist excerpt (pin names and nets, part order shuffled) for the footprints in the layout excerpt that follows; sources: Cadence DE-HDL packaged netlist, KiCad conversion of 03242023_DA0F0TMBIJ0_F0T_Motherboard_J_brd_V01_OCP.brd

PR1775  Q_RES  3.3 1% CHIP  pkg 0402LF  page 275 : A = SW_PVCCINFAON_CPU0_BOOT2 ; B = SW_PVCCINFAON_CPU0_BOOT2_R
C757  Q_CAP_DIFFBUS  DIFF BUS_0.22UF 6.3V 20% X6S  pkg C0201  page 176 : \1\ = P5E_CPU1_PE2_TX_C_DP<8> ; \2\ = P5E_CPU1_PE2_TX_DP<8>
PC2349  Q_CAP  1NF 50V 10% EMPTY  pkg 0402  page 303 : A = HSC_OCREF ; B = AGND_HSC

(kicad_pcb
	(version 20260206)
	(generator "pcbnew")
	(generator_version "10.0")
	(general
		(thickness 1.6)
		(legacy_teardrops no)
	)
	(paper "A4")
	(title_block
		(title "03242023_DA0F0TMBIJ0_F0T_Motherboard_J_brd_V01_OCP.brd")
		(comment 1 "Grand Teton / footprints 596-598 of 6105")
	)
	(layers
		(0 "F.Cu" signal "TOP")
		(4 "In1.Cu" signal "GND")
		(6 "In2.Cu" signal "IN1")
		(8 "In3.Cu" signal "GND1")
		(10 "In4.Cu" signal "IN2")
		(12 "In5.Cu" signal "GND2")
		(14 "In6.Cu" signal "IN3")
		(16 "In7.Cu" signal "GND3")
		(18 "In8.Cu" signal "VCC")
		(20 "In9.Cu" signal "VCC1")
		(22 "In10.Cu" signal "GND4")
		(24 "In11.Cu" signal "IN4")
		(26 "In12.Cu" signal "GND5")
		(28 "In13.Cu" signal "IN5")
		(30 "In14.Cu" signal "GND6")
		(32 "In15.Cu" signal "IN6")
		(34 "In16.Cu" signal "GND7")
		(2 "B.Cu" signal "BOTTOM")
		(9 "F.Adhes" user "F.Adhesive")
		(11 "B.Adhes" user "B.Adhesive")
		(13 "F.Paste" user "Package Geometry/Pastemask Top")
		(15 "B.Paste" user "Package Geometry/Pastemask Bottom")
		(5 "F.SilkS" user "Ref Des/Silkscreen Top")
		(7 "B.SilkS" user "Ref Des/Silkscreen Bottom")
		(1 "F.Mask" user "Board Geometry/Soldermask Top")
		(3 "B.Mask" user "Board Geometry/Soldermask Bottom")
		(17 "Dwgs.User" user "User.Drawings")
		(19 "Cmts.User" user "User.Comments")
		(21 "Eco1.User" user "User.Eco1")
		(23 "Eco2.User" user "User.Eco2")
		(25 "Edge.Cuts" user "Board Geometry/Outline")
		(27 "Margin" user)
		(31 "F.CrtYd" user "Package Geometry/Place Bound Top")
		(29 "B.CrtYd" user "Package Geometry/Place Bound Bottom")
		(35 "F.Fab" user "Ref Des/Assembly Top")
		(33 "B.Fab" user "Ref Des/Assembly Bottom")
	)
	(footprint ""
		(layer "F.Cu")
		(at 226.733608 -399.743422 180)
		(property "Reference" "PC2349"
			(at 0 0 180)
			(layer "F.SilkS")
			(hide yes)
			(effects
				(font
					(size 1.27 1.27)
				)
			)
		)
		(property "Value" ""
			(at 0 0 180)
			(layer "F.Fab")
			(effects
				(font
					(size 1.27 1.27)
				)
			)
		)
		(duplicate_pad_numbers_are_jumpers no)
		(fp_line
			(start 0.7874 0.4064)
			(end -0.7874 0.4064)
			(stroke
				(width 0.1524)
				(type default)
			)
			(layer "F.SilkS")
		)
		(fp_line
			(start 0.7874 -0.4064)
			(end 0.7874 0.4064)
			(stroke
				(width 0.1524)
				(type default)
			)
			(layer "F.SilkS")
		)
		(fp_line
			(start -0.7874 0.4064)
			(end -0.7874 -0.4064)
			(stroke
				(width 0.1524)
				(type default)
			)
			(layer "F.SilkS")
		)
		(fp_line
			(start -0.7874 -0.4064)
			(end 0.7874 -0.4064)
			(stroke
				(width 0.1524)
				(type default)
			)
			(layer "F.SilkS")
		)
		(fp_line
			(start 0.67945 0.3048)
			(end 0.120396 0.3048)
			(stroke
				(width 0.1)
				(type default)
			)
			(layer "F.Fab")
		)
		(fp_line
			(start 0.67945 -0.3048)
			(end 0.67945 0.3048)
			(stroke
				(width 0.1)
				(type default)
			)
			(layer "F.Fab")
		)
		(fp_line
			(start 0.12065 -0.2794)
			(end 0.12065 -0.3048)
			(stroke
				(width 0.1)
				(type default)
			)
			(layer "F.Fab")
		)
		(fp_line
			(start 0.12065 -0.3048)
			(end 0.67945 -0.3048)
			(stroke
				(width 0.1)
				(type default)
			)
			(layer "F.Fab")
		)
		(fp_line
			(start 0.120396 0.3048)
			(end 0.120396 0.2794)
			(stroke
				(width 0.1)
				(type default)
			)
			(layer "F.Fab")
		)
		(fp_line
			(start 0.120396 0.2794)
			(end -0.12065 0.2794)
			(stroke
				(width 0.1)
				(type default)
			)
			(layer "F.Fab")
		)
		(fp_line
			(start -0.12065 0.3048)
			(end -0.67945 0.3048)
			(stroke
				(width 0.1)
				(type default)
			)
			(layer "F.Fab")
		)
		(fp_line
			(start -0.12065 0.2794)
			(end -0.12065 0.3048)
			(stroke
				(width 0.1)
				(type default)
			)
			(layer "F.Fab")
		)
		(fp_line
			(start -0.12065 -0.2794)
			(end 0.12065 -0.2794)
			(stroke
				(width 0.1)
				(type default)
			)
			(layer "F.Fab")
		)
		(fp_line
			(start -0.12065 -0.305054)
			(end -0.12065 -0.2794)
			(stroke
				(width 0.1)
				(type default)
			)
			(layer "F.Fab")
		)
		(fp_line
			(start -0.67945 0.3048)
			(end -0.67945 -0.305054)
			(stroke
				(width 0.1)
				(type default)
			)
			(layer "F.Fab")
		)
		(fp_line
			(start -0.67945 -0.305054)
			(end -0.12065 -0.305054)
			(stroke
				(width 0.1)
				(type default)
			)
			(layer "F.Fab")
		)
		(pad "1" smd circle
			(at -0.40005 0 180)
			(size 0 0)
			(layers "F.Cu" "F.Mask" "F.Paste")
			(net "HSC_OCREF")
		)
		(pad "2" smd circle
			(at 0.40005 0 180)
			(size 0 0)
			(layers "F.Cu" "F.Mask" "F.Paste")
			(net "AGND_HSC")
		)
	)
	(footprint ""
		(layer "F.Cu")
		(at 141.572234 -402.371052 -90)
		(property "Reference" "C757"
			(at 0 0 270)
			(layer "F.SilkS")
			(hide yes)
			(effects
				(font
					(size 1.27 1.27)
				)
			)
		)
		(property "Value" ""
			(at 0 0 270)
			(layer "F.Fab")
			(effects
				(font
					(size 1.27 1.27)
				)
			)
		)
		(duplicate_pad_numbers_are_jumpers no)
		(fp_line
			(start -0.299974 0.150114)
			(end -0.299974 -0.150114)
			(stroke
				(width 0.1)
				(type default)
			)
			(layer "F.Fab")
		)
		(fp_line
			(start 0.299974 0.150114)
			(end -0.299974 0.150114)
			(stroke
				(width 0.1)
				(type default)
			)
			(layer "F.Fab")
		)
		(fp_line
			(start -0.299974 -0.150114)
			(end 0.299974 -0.150114)
			(stroke
				(width 0.1)
				(type default)
			)
			(layer "F.Fab")
		)
		(fp_line
			(start 0.299974 -0.150114)
			(end 0.299974 0.150114)
			(stroke
				(width 0.1)
				(type default)
			)
			(layer "F.Fab")
		)
		(pad "1" smd rect
			(at -0.2667 0 270)
			(size 0.3048 0.381)
			(layers "F.Cu" "F.Mask" "F.Paste")
			(net "P5E_CPU1_PE2_TX_C_DP<8>")
		)
		(pad "2" smd rect
			(at 0.2667 0 270)
			(size 0.3048 0.381)
			(layers "F.Cu" "F.Mask" "F.Paste")
			(net "P5E_CPU1_PE2_TX_DP<8>")
		)
	)
	(footprint ""
		(layer "F.Cu")
		(at 420.473632 -178.762914)
		(property "Reference" "PR1775"
			(at 0 0 0)
			(layer "F.SilkS")
			(hide yes)
			(effects
				(font
					(size 1.27 1.27)
				)
			)
		)
		(property "Value" ""
			(at 0 0 0)
			(layer "F.Fab")
			(effects
				(font
					(size 1.27 1.27)
				)
			)
		)
		(duplicate_pad_numbers_are_jumpers no)
		(fp_line
			(start -0.7874 -0.4064)
			(end 0.7874 -0.4064)
			(stroke
				(width 0.1524)
				(type default)
			)
			(layer "F.SilkS")
		)
		(fp_line
			(start -0.7874 0.4064)
			(end -0.7874 -0.4064)
			(stroke
				(width 0.1524)
				(type default)
			)
			(layer "F.SilkS")
		)
		(fp_line
			(start 0.7874 -0.4064)
			(end 0.7874 0.4064)
			(stroke
				(width 0.1524)
				(type default)
			)
			(layer "F.SilkS")
		)
		(fp_line
			(start 0.7874 0.4064)
			(end -0.7874 0.4064)
			(stroke
				(width 0.1524)
				(type default)
			)
			(layer "F.SilkS")
		)
		(fp_line
			(start -0.67945 -0.305054)
			(end -0.12065 -0.305054)
			(stroke
				(width 0.1)
				(type default)
			)
			(layer "F.Fab")
		)
		(fp_line
			(start -0.67945 0.3048)
			(end -0.67945 -0.305054)
			(stroke
				(width 0.1)
				(type default)
			)
			(layer "F.Fab")
		)
		(fp_line
			(start -0.12065 -0.305054)
			(end -0.12065 -0.2794)
			(stroke
				(width 0.1)
				(type default)
			)
			(layer "F.Fab")
		)
		(fp_line
			(start -0.12065 -0.2794)
			(end 0.12065 -0.2794)
			(stroke
				(width 0.1)
				(type default)
			)
			(layer "F.Fab")
		)
		(fp_line
			(start -0.12065 0.2794)
			(end -0.12065 0.3048)
			(stroke
				(width 0.1)
				(type default)
			)
			(layer "F.Fab")
		)
		(fp_line
			(start -0.12065 0.3048)
			(end -0.67945 0.3048)
			(stroke
				(width 0.1)
				(type default)
			)
			(layer "F.Fab")
		)
		(fp_line
			(start 0.120396 0.2794)
			(end -0.12065 0.2794)
			(stroke
				(width 0.1)
				(type default)
			)
			(layer "F.Fab")
		)
		(fp_line
			(start 0.120396 0.3048)
			(end 0.120396 0.2794)
			(stroke
				(width 0.1)
				(type default)
			)
			(layer "F.Fab")
		)
		(fp_line
			(start 0.12065 -0.3048)
			(end 0.67945 -0.3048)
			(stroke
				(width 0.1)
				(type default)
			)
			(layer "F.Fab")
		)
		(fp_line
			(start 0.12065 -0.2794)
			(end 0.12065 -0.3048)
			(stroke
				(width 0.1)
				(type default)
			)
			(layer "F.Fab")
		)
		(fp_line
			(start 0.67945 -0.3048)
			(end 0.67945 0.3048)
			(stroke
				(width 0.1)
				(type default)
			)
			(layer "F.Fab")
		)
		(fp_line
			(start 0.67945 0.3048)
			(end 0.120396 0.3048)
			(stroke
				(width 0.1)
				(type default)
			)
			(layer "F.Fab")
		)
		(pad "1" smd circle
			(at -0.40005 0)
			(size 0 0)
			(layers "F.Cu" "F.Mask" "F.Paste")
			(net "SW_PVCCINFAON_CPU0_BOOT2")
		)
		(pad "2" smd circle
			(at 0.40005 0)
			(size 0 0)
			(layers "F.Cu" "F.Mask" "F.Paste")
			(net "SW_PVCCINFAON_CPU0_BOOT2_R")
		)
	)
)
